(kicad_pcb
	(version 20260206)
	(generator "pcbnew")
	(generator_version "10.0")
	(general
		(thickness 1.6)
		(legacy_teardrops no)
	)
	(paper "A4")
	(title_block
		(title "Wiwynn_Tioga_Pass_MB.brd")
		(comment 1 "Tioga Pass / footprints 138-144 of 4770")
	)
	(layers
		(0 "F.Cu" signal "TOP")
		(4 "In1.Cu" signal "L2GND")
		(6 "In2.Cu" signal "L3")
		(8 "In3.Cu" signal "L4GND")
		(10 "In4.Cu" signal "L5")
		(12 "In5.Cu" signal "L6GND")
		(14 "In6.Cu" signal "L7VCC")
		(16 "In7.Cu" signal "L8VCC")
		(18 "In8.Cu" signal "L9GND")
		(20 "In9.Cu" signal "L10")
		(22 "In10.Cu" signal "L11GND")
		(24 "In11.Cu" signal "L12")
		(26 "In12.Cu" signal "L13GND")
		(2 "B.Cu" signal "BOTTOM")
		(9 "F.Adhes" user "F.Adhesive")
		(11 "B.Adhes" user "B.Adhesive")
		(13 "F.Paste" user "Package Geometry/Pastemask Top")
		(15 "B.Paste" user "Package Geometry/Pastemask Bottom")
		(5 "F.SilkS" user "Ref Des/Silkscreen Top")
		(7 "B.SilkS" user "Ref Des/Silkscreen Bottom")
		(1 "F.Mask" user "Board Geometry/Soldermask Top")
		(3 "B.Mask" user "Board Geometry/Soldermask Bottom")
		(17 "Dwgs.User" user "User.Drawings")
		(19 "Cmts.User" user "User.Comments")
		(21 "Eco1.User" user "User.Eco1")
		(23 "Eco2.User" user "User.Eco2")
		(25 "Edge.Cuts" user "Board Geometry/Outline")
		(27 "Margin" user)
		(31 "F.CrtYd" user "Package Geometry/Place Bound Top")
		(29 "B.CrtYd" user "Package Geometry/Place Bound Bottom")
		(35 "F.Fab" user "Ref Des/Assembly Top")
		(33 "B.Fab" user "Ref Des/Assembly Bottom")
	)
	(footprint ""
		(layer "F.Cu")
		(at 172.5676 -93.3958 180)
		(property "Reference" "R4C8"
			(at 0 0 180)
			(layer "F.SilkS")
			(hide yes)
			(effects
				(font
					(size 1.27 1.27)
				)
			)
		)
		(property "Value" ""
			(at 0 0 180)
			(layer "F.Fab")
			(effects
				(font
					(size 1.27 1.27)
				)
			)
		)
		(duplicate_pad_numbers_are_jumpers no)
		(fp_poly
			(pts
				(xy -0.2794 -0.1016) (xy 0.2794 -0.1016) (xy 0.2794 0.9906) (xy -0.2794 0.9906)
			)
			(stroke
				(width 0)
				(type default)
			)
			(fill no)
			(layer "F.CrtYd")
		)
		(fp_line
			(start 0.2794 0.9906)
			(end 0.2794 -0.1016)
			(stroke
				(width 0.1)
				(type default)
			)
			(layer "F.Fab")
		)
		(fp_line
			(start 0.2794 -0.1016)
			(end -0.2794 -0.1016)
			(stroke
				(width 0.1)
				(type default)
			)
			(layer "F.Fab")
		)
		(fp_line
			(start -0.2794 0.9906)
			(end 0.2794 0.9906)
			(stroke
				(width 0.1)
				(type default)
			)
			(layer "F.Fab")
		)
		(fp_line
			(start -0.2794 -0.1016)
			(end -0.2794 0.9906)
			(stroke
				(width 0.1)
				(type default)
			)
			(layer "F.Fab")
		)
		(pad "1" smd rect
			(at 0 0 180)
			(size 0.508 0.508)
			(layers "F.Cu" "F.Mask" "F.Paste")
			(net "P3V3_STBY")
		)
		(pad "2" smd rect
			(at 0 0.889 180)
			(size 0.508 0.508)
			(layers "F.Cu" "F.Mask" "F.Paste")
			(net "PU_GTL2014_2_DIR")
		)
		(zone
			(layer "F.Cu")
			(hatch none 0.5)
			(connect_pads
				(clearance 0)
			)
			(min_thickness 0.25)
			(keepout
				(tracks not_allowed)
				(vias allowed)
				(pads allowed)
				(copperpour not_allowed)
				(footprints allowed)
			)
			(placement
				(enabled no)
				(sheetname "")
			)
			(fill
				(thermal_gap 0.5)
				(thermal_bridge_width 0.5)
				(island_removal_mode 0)
			)
			(polygon
				(pts
					(xy 172.8216 -94.0308) (xy 172.3136 -94.0308) (xy 172.3136 -93.6498) (xy 172.8216 -93.6498)
				)
			)
		)
		(zone
			(layer "F.Cu")
			(hatch none 0.5)
			(connect_pads
				(clearance 0)
			)
			(min_thickness 0.25)
			(keepout
				(tracks allowed)
				(vias not_allowed)
				(pads allowed)
				(copperpour not_allowed)
				(footprints allowed)
			)
			(placement
				(enabled no)
				(sheetname "")
			)
			(fill
				(thermal_gap 0.5)
				(thermal_bridge_width 0.5)
				(island_removal_mode 0)
			)
			(polygon
				(pts
					(xy 172.8216 -93.6498) (xy 172.3136 -93.6498) (xy 172.3136 -94.0308) (xy 172.8216 -94.0308)
				)
			)
		)
	)
	(footprint ""
		(layer "F.Cu")
		(at 384.4798 -146.574764)
		(property "Reference" "L7A4"
			(at 3.378708 -4.251706 0)
			(unlocked yes)
			(layer "F.SilkS")
			(effects
				(font
					(size 0.4064 0.254)
					(thickness 0.1524)
				)
			)
		)
		(property "Value" ""
			(at 0 0 0)
			(layer "F.Fab")
			(effects
				(font
					(size 1.27 1.27)
				)
			)
		)
		(duplicate_pad_numbers_are_jumpers no)
		(fp_line
			(start -1.1303 -3.199892)
			(end 8.3693 -3.199892)
			(stroke
				(width 0.1524)
				(type default)
			)
			(layer "F.SilkS")
		)
		(fp_line
			(start -1.1303 -1.6637)
			(end -1.1303 -3.199892)
			(stroke
				(width 0.1524)
				(type default)
			)
			(layer "F.SilkS")
		)
		(fp_line
			(start -1.1303 3.199892)
			(end -1.1303 1.6637)
			(stroke
				(width 0.1524)
				(type default)
			)
			(layer "F.SilkS")
		)
		(fp_line
			(start 8.3693 -3.199892)
			(end 8.3693 -1.6637)
			(stroke
				(width 0.1524)
				(type default)
			)
			(layer "F.SilkS")
		)
		(fp_line
			(start 8.3693 1.6637)
			(end 8.3693 3.199892)
			(stroke
				(width 0.1524)
				(type default)
			)
			(layer "F.SilkS")
		)
		(fp_line
			(start 8.3693 3.199892)
			(end -1.1303 3.199892)
			(stroke
				(width 0.1524)
				(type default)
			)
			(layer "F.SilkS")
		)
		(fp_rect
			(start -1.1303 3.199892)
			(end 8.3693 -3.199892)
			(stroke
				(width 0)
				(type default)
			)
			(fill no)
			(layer "F.CrtYd")
		)
		(fp_line
			(start -1.1303 -3.199892)
			(end 8.3693 -3.199892)
			(stroke
				(width 0.1)
				(type default)
			)
			(layer "F.Fab")
		)
		(fp_line
			(start -1.1303 3.199892)
			(end -1.1303 -3.199892)
			(stroke
				(width 0.1)
				(type default)
			)
			(layer "F.Fab")
		)
		(fp_line
			(start 8.3693 -3.199892)
			(end 8.3693 3.199892)
			(stroke
				(width 0.1)
				(type default)
			)
			(layer "F.Fab")
		)
		(fp_line
			(start 8.3693 3.199892)
			(end -1.1303 3.199892)
			(stroke
				(width 0.1)
				(type default)
			)
			(layer "F.Fab")
		)
		(pad "1" smd rect
			(at 0 0)
			(size 3.683 2.667)
			(layers "F.Cu" "F.Mask" "F.Paste")
			(net "VR_P1V05_PCH_STBY_PH1_PHASE_SW")
		)
		(pad "2" smd rect
			(at 7.239 0)
			(size 3.683 2.667)
			(layers "F.Cu" "F.Mask" "F.Paste")
			(net "P1V05_PCH_STBY")
		)
	)
	(footprint ""
		(layer "F.Cu")
		(at 201.87158 -77.47 -90)
		(property "Reference" "RT27"
			(at 0 0 270)
			(layer "F.SilkS")
			(hide yes)
			(effects
				(font
					(size 1.27 1.27)
				)
			)
		)
		(property "Value" "*"
			(at -0.0254 -2.6289 270)
			(unlocked yes)
			(layer "F.Fab")
			(hide yes)
			(effects
				(font
					(size 1.27 1.016)
					(thickness 0.1524)
				)
			)
		)
		(property "Device Type" "1R3F-GP_RCL_GP-1R3F-GP,64.1R00A"
			(at -0.0254 -4.1529 270)
			(unlocked yes)
			(layer "F.Fab")
			(hide yes)
			(effects
				(font
					(size 1.27 1.016)
					(thickness 0.1524)
				)
			)
		)
		(duplicate_pad_numbers_are_jumpers no)
		(fp_line
			(start -0.4826 0)
			(end -0.2032 0)
			(stroke
				(width 0.2032)
				(type default)
			)
			(layer "F.SilkS")
		)
		(fp_line
			(start 0.2032 0)
			(end 0.4826 0)
			(stroke
				(width 0.2032)
				(type default)
			)
			(layer "F.SilkS")
		)
		(fp_rect
			(start -0.5842 1.3335)
			(end 0.5842 -1.3335)
			(stroke
				(width 0)
				(type default)
			)
			(fill no)
			(layer "F.CrtYd")
		)
		(fp_rect
			(start -0.5842 1.3335)
			(end 0.5842 -1.3335)
			(stroke
				(width 0)
				(type default)
			)
			(fill no)
			(layer "F.Fab")
		)
		(pad "1" smd custom
			(at 0 -0.762 270)
			(size 0.2159 0.2159)
			(layers "F.Cu" "F.Mask" "F.Paste")
			(net "VR_PVCCIN_CPU0_PHASE4_RC")
			(options
				(clearance outline)
				(anchor circle)
			)
			(primitives
				(gr_poly
					(pts
						(arc
							(start -0.3302 -0.4318)
							(mid -0.402042 -0.402042)
							(end -0.4318 -0.3302)
						)
						(arc
							(start -0.4318 0.3302)
							(mid -0.402042 0.402042)
							(end -0.3302 0.4318)
						)
						(arc
							(start 0.3302 0.4318)
							(mid 0.402042 0.402042)
							(end 0.4318 0.3302)
						)
						(arc
							(start 0.4318 -0.3302)
							(mid 0.402042 -0.402042)
							(end 0.3302 -0.4318)
						)
					)
					(width 0)
					(fill yes)
				)
			)
		)
		(pad "2" smd custom
			(at 0 0.762 270)
			(size 0.2159 0.2159)
			(layers "F.Cu" "F.Mask" "F.Paste")
			(net "GND")
			(options
				(clearance outline)
				(anchor circle)
			)
			(primitives
				(gr_poly
					(pts
						(arc
							(start -0.3302 -0.4318)
							(mid -0.402042 -0.402042)
							(end -0.4318 -0.3302)
						)
						(arc
							(start -0.4318 0.3302)
							(mid -0.402042 0.402042)
							(end -0.3302 0.4318)
						)
						(arc
							(start 0.3302 0.4318)
							(mid 0.402042 0.402042)
							(end 0.4318 0.3302)
						)
						(arc
							(start 0.4318 -0.3302)
							(mid 0.402042 -0.402042)
							(end 0.3302 -0.4318)
						)
					)
					(width 0)
					(fill yes)
				)
			)
		)
	)
	(footprint ""
		(layer "F.Cu")
		(at 395.351 -88.2015)
		(property "Reference" "R2U6"
			(at 0 0 0)
			(layer "F.SilkS")
			(hide yes)
			(effects
				(font
					(size 1.27 1.27)
				)
			)
		)
		(property "Value" ""
			(at 0 0 0)
			(layer "F.Fab")
			(effects
				(font
					(size 1.27 1.27)
				)
			)
		)
		(duplicate_pad_numbers_are_jumpers no)
		(fp_poly
			(pts
				(xy -0.2794 -0.1016) (xy 0.2794 -0.1016) (xy 0.2794 0.9906) (xy -0.2794 0.9906)
			)
			(stroke
				(width 0)
				(type default)
			)
			(fill no)
			(layer "F.CrtYd")
		)
		(fp_line
			(start -0.2794 -0.1016)
			(end -0.2794 0.9906)
			(stroke
				(width 0.1)
				(type default)
			)
			(layer "F.Fab")
		)
		(fp_line
			(start -0.2794 0.9906)
			(end 0.2794 0.9906)
			(stroke
				(width 0.1)
				(type default)
			)
			(layer "F.Fab")
		)
		(fp_line
			(start 0.2794 -0.1016)
			(end -0.2794 -0.1016)
			(stroke
				(width 0.1)
				(type default)
			)
			(layer "F.Fab")
		)
		(fp_line
			(start 0.2794 0.9906)
			(end 0.2794 -0.1016)
			(stroke
				(width 0.1)
				(type default)
			)
			(layer "F.Fab")
		)
		(pad "1" smd rect
			(at 0 0)
			(size 0.508 0.508)
			(layers "F.Cu" "F.Mask" "F.Paste")
			(net "SMB_LAN_STBY_LVC3_SCL_R1")
		)
		(pad "2" smd rect
			(at 0 0.889)
			(size 0.508 0.508)
			(layers "F.Cu" "F.Mask" "F.Paste")
			(net "SMB_LAN_STBY_LVC3_SCL")
		)
		(zone
			(layer "F.Cu")
			(hatch none 0.5)
			(connect_pads
				(clearance 0)
			)
			(min_thickness 0.25)
			(keepout
				(tracks allowed)
				(vias not_allowed)
				(pads allowed)
				(copperpour not_allowed)
				(footprints allowed)
			)
			(placement
				(enabled no)
				(sheetname "")
			)
			(fill
				(thermal_gap 0.5)
				(thermal_bridge_width 0.5)
				(island_removal_mode 0)
			)
			(polygon
				(pts
					(xy 395.097 -87.9475) (xy 395.605 -87.9475) (xy 395.605 -87.5665) (xy 395.097 -87.5665)
				)
			)
		)
		(zone
			(layer "F.Cu")
			(hatch none 0.5)
			(connect_pads
				(clearance 0)
			)
			(min_thickness 0.25)
			(keepout
				(tracks not_allowed)
				(vias allowed)
				(pads allowed)
				(copperpour not_allowed)
				(footprints allowed)
			)
			(placement
				(enabled no)
				(sheetname "")
			)
			(fill
				(thermal_gap 0.5)
				(thermal_bridge_width 0.5)
				(island_removal_mode 0)
			)
			(polygon
				(pts
					(xy 395.097 -87.5665) (xy 395.605 -87.5665) (xy 395.605 -87.9475) (xy 395.097 -87.9475)
				)
			)
		)
	)
	(footprint ""
		(layer "F.Cu")
		(at 354.89769 -139.965176 -90)
		(property "Reference" "C7A29"
			(at 0 0 270)
			(layer "F.SilkS")
			(hide yes)
			(effects
				(font
					(size 1.27 1.27)
				)
			)
		)
		(property "Value" ""
			(at 0 0 270)
			(layer "F.Fab")
			(effects
				(font
					(size 1.27 1.27)
				)
			)
		)
		(duplicate_pad_numbers_are_jumpers no)
		(fp_rect
			(start 0.3048 0.9906)
			(end -0.3048 -0.1016)
			(stroke
				(width 0)
				(type default)
			)
			(fill no)
			(layer "F.CrtYd")
		)
		(fp_line
			(start -0.3048 0.9906)
			(end 0.3048 0.9906)
			(stroke
				(width 0.1)
				(type default)
			)
			(layer "F.Fab")
		)
		(fp_line
			(start 0.3048 0.9906)
			(end 0.3048 -0.1016)
			(stroke
				(width 0.1)
				(type default)
			)
			(layer "F.Fab")
		)
		(fp_line
			(start -0.3048 -0.1016)
			(end -0.3048 0.9906)
			(stroke
				(width 0.1)
				(type default)
			)
			(layer "F.Fab")
		)
		(fp_line
			(start 0.3048 -0.1016)
			(end -0.3048 -0.1016)
			(stroke
				(width 0.1)
				(type default)
			)
			(layer "F.Fab")
		)
		(pad "1" smd rect
			(at 0 0 270)
			(size 0.508 0.508)
			(layers "F.Cu" "F.Mask" "F.Paste")
			(net "A_TSENSE_PVDDQ_DEF")
		)
		(pad "2" smd rect
			(at 0 0.889 270)
			(size 0.508 0.508)
			(layers "F.Cu" "F.Mask" "F.Paste")
			(net "GND")
		)
		(zone
			(layer "F.Cu")
			(hatch none 0.5)
			(connect_pads
				(clearance 0)
			)
			(min_thickness 0.25)
			(keepout
				(tracks not_allowed)
				(vias allowed)
				(pads allowed)
				(copperpour not_allowed)
				(footprints allowed)
			)
			(placement
				(enabled no)
				(sheetname "")
			)
			(fill
				(thermal_gap 0.5)
				(thermal_bridge_width 0.5)
				(island_removal_mode 0)
			)
			(polygon
				(pts
					(xy 354.26269 -139.711176) (xy 354.64369 -139.711176) (xy 354.64369 -140.219176) (xy 354.26269 -140.219176)
				)
			)
		)
		(zone
			(layer "F.Cu")
			(hatch none 0.5)
			(connect_pads
				(clearance 0)
			)
			(min_thickness 0.25)
			(keepout
				(tracks allowed)
				(vias not_allowed)
				(pads allowed)
				(copperpour not_allowed)
				(footprints allowed)
			)
			(placement
				(enabled no)
				(sheetname "")
			)
			(fill
				(thermal_gap 0.5)
				(thermal_bridge_width 0.5)
				(island_removal_mode 0)
			)
			(polygon
				(pts
					(xy 354.26269 -139.711176) (xy 354.64369 -139.711176) (xy 354.64369 -140.219176) (xy 354.26269 -140.219176)
				)
			)
		)
	)
	(footprint ""
		(layer "F.Cu")
		(at 0.889 -134.3152 -90)
		(property "Reference" "C1B20"
			(at 0 0 270)
			(layer "F.SilkS")
			(hide yes)
			(effects
				(font
					(size 1.27 1.27)
				)
			)
		)
		(property "Value" ""
			(at 0 0 270)
			(layer "F.Fab")
			(effects
				(font
					(size 1.27 1.27)
				)
			)
		)
		(duplicate_pad_numbers_are_jumpers no)
		(fp_poly
			(pts
				(xy 0.3048 -0.1016) (xy 0.3048 0.9906) (xy -0.3048 0.9906) (xy -0.3048 -0.1016)
			)
			(stroke
				(width 0)
				(type default)
			)
			(fill no)
			(layer "F.CrtYd")
		)
		(fp_line
			(start -0.3048 0.9906)
			(end 0.3048 0.9906)
			(stroke
				(width 0.1)
				(type default)
			)
			(layer "F.Fab")
		)
		(fp_line
			(start 0.3048 0.9906)
			(end 0.3048 -0.1016)
			(stroke
				(width 0.1)
				(type default)
			)
			(layer "F.Fab")
		)
		(fp_line
			(start -0.3048 -0.1016)
			(end -0.3048 0.9906)
			(stroke
				(width 0.1)
				(type default)
			)
			(layer "F.Fab")
		)
		(fp_line
			(start 0.3048 -0.1016)
			(end -0.3048 -0.1016)
			(stroke
				(width 0.1)
				(type default)
			)
			(layer "F.Fab")
		)
		(pad "1" smd rect
			(at 0 0 270)
			(size 0.508 0.508)
			(layers "F.Cu" "F.Mask" "F.Paste")
			(net "VR_PVDDQ_KLM_PH1_VCIN")
		)
		(pad "2" smd rect
			(at 0 0.889 270)
			(size 0.508 0.508)
			(layers "F.Cu" "F.Mask" "F.Paste")
			(net "GND")
		)
		(zone
			(layer "F.Cu")
			(hatch none 0.5)
			(connect_pads
				(clearance 0)
			)
			(min_thickness 0.25)
			(keepout
				(tracks not_allowed)
				(vias allowed)
				(pads allowed)
				(copperpour not_allowed)
				(footprints allowed)
			)
			(placement
				(enabled no)
				(sheetname "")
			)
			(fill
				(thermal_gap 0.5)
				(thermal_bridge_width 0.5)
				(island_removal_mode 0)
			)
			(polygon
				(pts
					(xy 0.254 -134.5692) (xy 0.254 -134.0612) (xy 0.635 -134.0612) (xy 0.635 -134.5692)
				)
			)
		)
		(zone
			(layer "F.Cu")
			(hatch none 0.5)
			(connect_pads
				(clearance 0)
			)
			(min_thickness 0.25)
			(keepout
				(tracks allowed)
				(vias not_allowed)
				(pads allowed)
				(copperpour not_allowed)
				(footprints allowed)
			)
			(placement
				(enabled no)
				(sheetname "")
			)
			(fill
				(thermal_gap 0.5)
				(thermal_bridge_width 0.5)
				(island_removal_mode 0)
			)
			(polygon
				(pts
					(xy 0.635 -134.5692) (xy 0.635 -134.0612) (xy 0.254 -134.0612) (xy 0.254 -134.5692)
				)
			)
		)
	)
	(footprint ""
		(layer "F.Cu")
		(at 379.222 -88.2015)
		(property "Reference" "R25W69"
			(at -0.8382 -0.67818 0)
			(unlocked yes)
			(layer "F.SilkS")
			(effects
				(font
					(size 0.4064 0.254)
					(thickness 0.1524)
				)
				(justify left)
			)
		)
		(property "Value" ""
			(at 0 0 0)
			(layer "F.Fab")
			(effects
				(font
					(size 1.27 1.27)
				)
			)
		)
		(duplicate_pad_numbers_are_jumpers no)
		(fp_poly
			(pts
				(xy -0.2794 -0.1016) (xy 0.2794 -0.1016) (xy 0.2794 0.9906) (xy -0.2794 0.9906)
			)
			(stroke
				(width 0)
				(type default)
			)
			(fill no)
			(layer "F.CrtYd")
		)
		(fp_line
			(start -0.2794 -0.1016)
			(end -0.2794 0.9906)
			(stroke
				(width 0.1)
				(type default)
			)
			(layer "F.Fab")
		)
		(fp_line
			(start -0.2794 0.9906)
			(end 0.2794 0.9906)
			(stroke
				(width 0.1)
				(type default)
			)
			(layer "F.Fab")
		)
		(fp_line
			(start 0.2794 -0.1016)
			(end -0.2794 -0.1016)
			(stroke
				(width 0.1)
				(type default)
			)
			(layer "F.Fab")
		)
		(fp_line
			(start 0.2794 0.9906)
			(end 0.2794 -0.1016)
			(stroke
				(width 0.1)
				(type default)
			)
			(layer "F.Fab")
		)
		(pad "1" smd rect
			(at 0 0)
			(size 0.508 0.508)
			(layers "F.Cu" "F.Mask" "F.Paste")
			(net "LPC_LAD1_IO1")
		)
		(pad "2" smd rect
			(at 0 0.889)
			(size 0.508 0.508)
			(layers "F.Cu" "F.Mask" "F.Paste")
			(net "LPC_LAD1_IO1_R")
		)
		(zone
			(layer "F.Cu")
			(hatch none 0.5)
			(connect_pads
				(clearance 0)
			)
			(min_thickness 0.25)
			(keepout
				(tracks allowed)
				(vias not_allowed)
				(pads allowed)
				(copperpour not_allowed)
				(footprints allowed)
			)
			(placement
				(enabled no)
				(sheetname "")
			)
			(fill
				(thermal_gap 0.5)
				(thermal_bridge_width 0.5)
				(island_removal_mode 0)
			)
			(polygon
				(pts
					(xy 378.968 -87.9475) (xy 379.476 -87.9475) (xy 379.476 -87.5665) (xy 378.968 -87.5665)
				)
			)
		)
		(zone
			(layer "F.Cu")
			(hatch none 0.5)
			(connect_pads
				(clearance 0)
			)
			(min_thickness 0.25)
			(keepout
				(tracks not_allowed)
				(vias allowed)
				(pads allowed)
				(copperpour not_allowed)
				(footprints allowed)
			)
			(placement
				(enabled no)
				(sheetname "")
			)
			(fill
				(thermal_gap 0.5)
				(thermal_bridge_width 0.5)
				(island_removal_mode 0)
			)
			(polygon
				(pts
					(xy 378.968 -87.5665) (xy 379.476 -87.5665) (xy 379.476 -87.9475) (xy 378.968 -87.9475)
				)
			)
		)
	)
)
